# BASEBOARD_FAB2 (Tioga Pass) — schematic netlist excerpt (pin names and nets, part order shuffled) for the footprints in the layout excerpt that follows; sources: Cadence DE-HDL packaged netlist, KiCad conversion of Wiwynn_Tioga_Pass_MB.brd

C3L16  CAP  10UF 16V 10% X6S  pkg 0805  page 219 : A = VR_FET_SW_P12V_STBY_PVDDQ_DEF ; B = GND
R9F27  RES  0.0 5% CHIP  pkg 0402  page 158 : A = UART_MUX_OUT_R ; B = SPA_MID_DBG_TX
C1U19  CAP  1.0UF 16V 10% X6S  pkg 0402  page 152 : A = P3V3 ; B = GND

(kicad_pcb
	(version 20260206)
	(generator "pcbnew")
	(generator_version "10.0")
	(general
		(thickness 1.6)
		(legacy_teardrops no)
	)
	(paper "A4")
	(title_block
		(title "Wiwynn_Tioga_Pass_MB.brd")
		(comment 1 "Tioga Pass / footprints 4577-4579 of 4770")
	)
	(layers
		(0 "F.Cu" signal "TOP")
		(4 "In1.Cu" signal "L2GND")
		(6 "In2.Cu" signal "L3")
		(8 "In3.Cu" signal "L4GND")
		(10 "In4.Cu" signal "L5")
		(12 "In5.Cu" signal "L6GND")
		(14 "In6.Cu" signal "L7VCC")
		(16 "In7.Cu" signal "L8VCC")
		(18 "In8.Cu" signal "L9GND")
		(20 "In9.Cu" signal "L10")
		(22 "In10.Cu" signal "L11GND")
		(24 "In11.Cu" signal "L12")
		(26 "In12.Cu" signal "L13GND")
		(2 "B.Cu" signal "BOTTOM")
		(9 "F.Adhes" user "F.Adhesive")
		(11 "B.Adhes" user "B.Adhesive")
		(13 "F.Paste" user "Package Geometry/Pastemask Top")
		(15 "B.Paste" user "Package Geometry/Pastemask Bottom")
		(5 "F.SilkS" user "Ref Des/Silkscreen Top")
		(7 "B.SilkS" user "Ref Des/Silkscreen Bottom")
		(1 "F.Mask" user "Board Geometry/Soldermask Top")
		(3 "B.Mask" user "Board Geometry/Soldermask Bottom")
		(17 "Dwgs.User" user "User.Drawings")
		(19 "Cmts.User" user "User.Comments")
		(21 "Eco1.User" user "User.Eco1")
		(23 "Eco2.User" user "User.Eco2")
		(25 "Edge.Cuts" user "Board Geometry/Outline")
		(27 "Margin" user)
		(31 "F.CrtYd" user "Package Geometry/Place Bound Top")
		(29 "B.CrtYd" user "Package Geometry/Place Bound Bottom")
		(35 "F.Fab" user "Ref Des/Assembly Top")
		(33 "B.Fab" user "Ref Des/Assembly Bottom")
	)
	(footprint ""
		(layer "B.Cu")
		(at 497.794534 -38.029896 -90)
		(property "Reference" "R9F27"
			(at 0 0 90)
			(layer "B.SilkS")
			(hide yes)
			(effects
				(font
					(size 1.27 1.27)
				)
				(justify mirror)
			)
		)
		(property "Value" ""
			(at 0 0 90)
			(layer "B.Fab")
			(effects
				(font
					(size 1.27 1.27)
				)
				(justify mirror)
			)
		)
		(duplicate_pad_numbers_are_jumpers no)
		(fp_poly
			(pts
				(xy 0.2794 -0.1016) (xy -0.2794 -0.1016) (xy -0.2794 0.9906) (xy 0.2794 0.9906)
			)
			(stroke
				(width 0)
				(type default)
			)
			(fill no)
			(layer "B.CrtYd")
		)
		(fp_line
			(start -0.2794 0.9906)
			(end -0.2794 -0.1016)
			(stroke
				(width 0.1)
				(type default)
			)
			(layer "B.Fab")
		)
		(fp_line
			(start 0.2794 0.9906)
			(end -0.2794 0.9906)
			(stroke
				(width 0.1)
				(type default)
			)
			(layer "B.Fab")
		)
		(fp_line
			(start -0.2794 -0.1016)
			(end 0.2794 -0.1016)
			(stroke
				(width 0.1)
				(type default)
			)
			(layer "B.Fab")
		)
		(fp_line
			(start 0.2794 -0.1016)
			(end 0.2794 0.9906)
			(stroke
				(width 0.1)
				(type default)
			)
			(layer "B.Fab")
		)
		(pad "1" smd rect
			(at 0 0 90)
			(size 0.508 0.508)
			(layers "B.Cu" "B.Mask" "B.Paste")
			(net "UART_MUX_OUT_R")
		)
		(pad "2" smd rect
			(at 0 0.889 90)
			(size 0.508 0.508)
			(layers "B.Cu" "B.Mask" "B.Paste")
			(net "SPA_MID_DBG_TX")
		)
		(zone
			(layer "B.Cu")
			(hatch none 0.5)
			(connect_pads
				(clearance 0)
			)
			(min_thickness 0.25)
			(keepout
				(tracks not_allowed)
				(vias allowed)
				(pads allowed)
				(copperpour not_allowed)
				(footprints allowed)
			)
			(placement
				(enabled no)
				(sheetname "")
			)
			(fill
				(thermal_gap 0.5)
				(thermal_bridge_width 0.5)
				(island_removal_mode 0)
			)
			(polygon
				(pts
					(xy 497.159534 -37.775896) (xy 497.159534 -38.283896) (xy 497.540534 -38.283896) (xy 497.540534 -37.775896)
				)
			)
		)
		(zone
			(layer "B.Cu")
			(hatch none 0.5)
			(connect_pads
				(clearance 0)
			)
			(min_thickness 0.25)
			(keepout
				(tracks allowed)
				(vias not_allowed)
				(pads allowed)
				(copperpour not_allowed)
				(footprints allowed)
			)
			(placement
				(enabled no)
				(sheetname "")
			)
			(fill
				(thermal_gap 0.5)
				(thermal_bridge_width 0.5)
				(island_removal_mode 0)
			)
			(polygon
				(pts
					(xy 497.540534 -37.775896) (xy 497.540534 -38.283896) (xy 497.159534 -38.283896) (xy 497.159534 -37.775896)
				)
			)
		)
	)
	(footprint ""
		(layer "B.Cu")
		(at 431.609246 -17.585182 90)
		(property "Reference" "C1U19"
			(at 0 0 90)
			(layer "B.SilkS")
			(hide yes)
			(effects
				(font
					(size 1.27 1.27)
				)
				(justify mirror)
			)
		)
		(property "Value" ""
			(at 0 0 90)
			(layer "B.Fab")
			(effects
				(font
					(size 1.27 1.27)
				)
				(justify mirror)
			)
		)
		(duplicate_pad_numbers_are_jumpers no)
		(fp_poly
			(pts
				(xy -0.3048 -0.1016) (xy -0.3048 0.9906) (xy 0.3048 0.9906) (xy 0.3048 -0.1016)
			)
			(stroke
				(width 0)
				(type default)
			)
			(fill no)
			(layer "B.CrtYd")
		)
		(fp_line
			(start 0.3048 -0.1016)
			(end 0.3048 0.9906)
			(stroke
				(width 0.1)
				(type default)
			)
			(layer "B.Fab")
		)
		(fp_line
			(start -0.3048 -0.1016)
			(end 0.3048 -0.1016)
			(stroke
				(width 0.1)
				(type default)
			)
			(layer "B.Fab")
		)
		(fp_line
			(start 0.3048 0.9906)
			(end -0.3048 0.9906)
			(stroke
				(width 0.1)
				(type default)
			)
			(layer "B.Fab")
		)
		(fp_line
			(start -0.3048 0.9906)
			(end -0.3048 -0.1016)
			(stroke
				(width 0.1)
				(type default)
			)
			(layer "B.Fab")
		)
		(pad "1" smd rect
			(at 0 0 270)
			(size 0.508 0.508)
			(layers "B.Cu" "B.Mask" "B.Paste")
			(net "P3V3")
		)
		(pad "2" smd rect
			(at 0 0.889 270)
			(size 0.508 0.508)
			(layers "B.Cu" "B.Mask" "B.Paste")
			(net "GND")
		)
		(zone
			(layer "B.Cu")
			(hatch none 0.5)
			(connect_pads
				(clearance 0)
			)
			(min_thickness 0.25)
			(keepout
				(tracks allowed)
				(vias not_allowed)
				(pads allowed)
				(copperpour not_allowed)
				(footprints allowed)
			)
			(placement
				(enabled no)
				(sheetname "")
			)
			(fill
				(thermal_gap 0.5)
				(thermal_bridge_width 0.5)
				(island_removal_mode 0)
			)
			(polygon
				(pts
					(xy 431.863246 -17.839182) (xy 431.863246 -17.331182) (xy 432.244246 -17.331182) (xy 432.244246 -17.839182)
				)
			)
		)
		(zone
			(layer "B.Cu")
			(hatch none 0.5)
			(connect_pads
				(clearance 0)
			)
			(min_thickness 0.25)
			(keepout
				(tracks not_allowed)
				(vias allowed)
				(pads allowed)
				(copperpour not_allowed)
				(footprints allowed)
			)
			(placement
				(enabled no)
				(sheetname "")
			)
			(fill
				(thermal_gap 0.5)
				(thermal_bridge_width 0.5)
				(island_removal_mode 0)
			)
			(polygon
				(pts
					(xy 432.244246 -17.839182) (xy 432.244246 -17.331182) (xy 431.863246 -17.331182) (xy 431.863246 -17.839182)
				)
			)
		)
	)
	(footprint ""
		(layer "B.Cu")
		(at 348.615 -142.914624 -90)
		(property "Reference" "C3L16"
			(at 0 0 90)
			(layer "B.SilkS")
			(hide yes)
			(effects
				(font
					(size 1.27 1.27)
				)
				(justify mirror)
			)
		)
		(property "Value" ""
			(at 0 0 90)
			(layer "B.Fab")
			(effects
				(font
					(size 1.27 1.27)
				)
				(justify mirror)
			)
		)
		(duplicate_pad_numbers_are_jumpers no)
		(fp_poly
			(pts
				(xy 0.7239 -0.2159) (xy -0.7239 -0.2159) (xy -0.7239 1.9939) (xy 0.7239 1.9939)
			)
			(stroke
				(width 0)
				(type default)
			)
			(fill no)
			(layer "B.CrtYd")
		)
		(fp_line
			(start -0.7239 1.9939)
			(end -0.7239 -0.2159)
			(stroke
				(width 0.1)
				(type default)
			)
			(layer "B.Fab")
		)
		(fp_line
			(start 0.7239 1.9939)
			(end -0.7239 1.9939)
			(stroke
				(width 0.1)
				(type default)
			)
			(layer "B.Fab")
		)
		(fp_line
			(start -0.7239 -0.2159)
			(end 0.7239 -0.2159)
			(stroke
				(width 0.1)
				(type default)
			)
			(layer "B.Fab")
		)
		(fp_line
			(start 0.7239 -0.2159)
			(end 0.7239 1.9939)
			(stroke
				(width 0.1)
				(type default)
			)
			(layer "B.Fab")
		)
		(pad "1" smd rect
			(at 0 0 90)
			(size 1.27 1.016)
			(layers "B.Cu" "B.Mask" "B.Paste")
			(net "VR_FET_SW_P12V_STBY_PVDDQ_DEF")
		)
		(pad "2" smd rect
			(at 0 1.778 90)
			(size 1.27 1.016)
			(layers "B.Cu" "B.Mask" "B.Paste")
			(net "GND")
		)
		(zone
			(layer "B.Cu")
			(hatch none 0.5)
			(connect_pads
				(clearance 0)
			)
			(min_thickness 0.25)
			(keepout
				(tracks not_allowed)
				(vias allowed)
				(pads allowed)
				(copperpour not_allowed)
				(footprints allowed)
			)
			(placement
				(enabled no)
				(sheetname "")
			)
			(fill
				(thermal_gap 0.5)
				(thermal_bridge_width 0.5)
				(island_removal_mode 0)
			)
			(polygon
				(pts
					(xy 348.107 -142.279624) (xy 348.107 -143.549624) (xy 347.345 -143.549624) (xy 347.345 -142.279624)
				)
			)
		)
	)
)
